(kicad_pcb
	(version 20241229)
	(generator "pcbnew")
	(generator_version "9.0")
	(general
		(thickness 1.711)
		(legacy_teardrops no)
	)
	(paper "A4")
	(title_block
		(title "Antmicro Baseboard for Jetson AGX Thor")
		(date "2026-02-18")
		(rev "1.1.0")
		(company "Antmicro Ltd")
		(comment 1 "www.antmicro.com")
		(comment 9 "footprint 110 of 1170 (J1), pads 243-322 of 699")
	)
	(layers
		(0 "F.Cu" signal)
		(4 "In1.Cu" signal)
		(6 "In2.Cu" signal)
		(8 "In3.Cu" signal)
		(10 "In4.Cu" jumper)
		(12 "In5.Cu" signal)
		(14 "In6.Cu" signal)
		(16 "In7.Cu" signal)
		(18 "In8.Cu" signal)
		(2 "B.Cu" signal)
		(9 "F.Adhes" user "F.Adhesive")
		(11 "B.Adhes" user "B.Adhesive")
		(13 "F.Paste" user)
		(15 "B.Paste" user)
		(5 "F.SilkS" user "F.Silkscreen")
		(7 "B.SilkS" user "B.Silkscreen")
		(1 "F.Mask" user)
		(3 "B.Mask" user)
		(17 "Dwgs.User" user "User.Drawings")
		(19 "Cmts.User" user "User.Comments")
		(21 "Eco1.User" user "User.Eco1")
		(23 "Eco2.User" user "User.Eco2")
		(25 "Edge.Cuts" user)
		(27 "Margin" user)
		(31 "F.CrtYd" user "F.Courtyard")
		(29 "B.CrtYd" user "B.Courtyard")
		(35 "F.Fab" user)
		(33 "B.Fab" user)
	)
	(footprint "antmicro-footprints:Conn_Hermaphroditic_Molex_203456-0003_mirrored"
		(locked yes)
		(layer "F.Cu")
		(at 116.530532 78.15)
		(descr "Mirrored version of: https://www.molex.com/content/dam/molex/molex-dot-com/products/automated/en-us/salesdrawingpdf/203/203456/2034560003_sd.pdf")
		(property "Reference" "J1"
			(at -32.25 -11.2 180)
			(layer "F.SilkS")
			(effects
				(font
					(size 0.7 0.7)
					(thickness 0.15)
				)
				(justify right top)
			)
		)
		(property "Value" "Hermaphroditic_Molex_203456-0003_CUSTOM_Jetson_AGX_Thor_H8mm"
			(at 0.1 12.9 0)
			(layer "F.Fab")
			(effects
				(font
					(size 0.7 0.7)
					(thickness 0.15)
				)
				(justify right top)
			)
		)
		(property "Datasheet" "https://www.molex.com/content/dam/molex/molex-dot-com/products/automated/en-us/salesdrawingpdf/203/203456/2034560003_sd.pdf?inline"
			(at 0.1 0.2 0)
			(layer "F.Fab")
			(hide yes)
			(effects
				(font
					(size 0.7 0.7)
					(thickness 0.15)
				)
				(justify right top)
			)
		)
		(property "Description" "Mirror Mezz Hermaphroditic Connector, 5.50mm Connector Height, BGA-Attach Mounting, 7 Pair, 11 Row, 699 Circuits, 0.76µm Gold Plating, without Pegs"
			(at 0.1 0.2 0)
			(layer "F.Fab")
			(hide yes)
			(effects
				(font
					(size 0.7 0.7)
					(thickness 0.15)
				)
				(justify right top)
			)
		)
		(property "MPN" "203456-0003"
			(at 0 0 0)
			(unlocked yes)
			(layer "F.Fab")
			(hide yes)
			(effects
				(font
					(size 1 1)
					(thickness 0.15)
				)
			)
		)
		(property "Manufacturer" "Molex"
			(at 0 0 0)
			(unlocked yes)
			(layer "F.Fab")
			(hide yes)
			(effects
				(font
					(size 1 1)
					(thickness 0.15)
				)
			)
		)
		(property "Author" "Antmicro"
			(at 0 0 0)
			(unlocked yes)
			(layer "F.Fab")
			(hide yes)
			(effects
				(font
					(size 1 1)
					(thickness 0.15)
				)
			)
		)
		(property "License" "Apache-2.0"
			(at 0 0 0)
			(unlocked yes)
			(layer "F.Fab")
			(hide yes)
			(effects
				(font
					(size 1 1)
					(thickness 0.15)
				)
			)
		)
		(sheetname "/SoM_IO/")
		(sheetfile "som_io.kicad_sch")
		(solder_mask_margin 0.05)
		(attr smd)
		(pad "D56" smd circle
			(at 22.3 3 90)
			(size 0.5 0.5)
			(layers "F.Cu" "F.Mask" "F.Paste")
			(net 75 "/Expansion connector/SPI3.MISO")
			(pinfunction "SPI3_MISO")
			(pintype "bidirectional")
		)
		(pad "D57" smd circle
			(at 23.2 3 90)
			(size 0.5 0.5)
			(layers "F.Cu" "F.Mask" "F.Paste")
			(net 1 "GND")
			(pinfunction "GND")
			(pintype "passive")
		)
		(pad "D58" smd circle
			(at 24.1 3 90)
			(size 0.5 0.5)
			(layers "F.Cu" "F.Mask" "F.Paste")
			(net 688 "/SoM_IO2/JTAG_TDO")
			(pinfunction "JTAG_TDO")
			(pintype "passive")
		)
		(pad "D59" smd circle
			(at 25 3 90)
			(size 0.5 0.5)
			(layers "F.Cu" "F.Mask" "F.Paste")
			(net 600 "/Expansion connector/CAN2.DOUT")
			(pinfunction "CAN2_DOUT")
			(pintype "output")
		)
		(pad "D60" smd circle
			(at 25.9 3 90)
			(size 0.5 0.5)
			(layers "F.Cu" "F.Mask" "F.Paste")
			(net 409 "/Expansion connector/SPI2.~{CS0}")
			(pinfunction "SPI2_CS0_N")
			(pintype "bidirectional")
		)
		(pad "D61" smd circle
			(at 26.8 3 90)
			(size 0.5 0.5)
			(layers "F.Cu" "F.Mask" "F.Paste")
			(net 983 "/CSI/I2C_{CAM}.SCL")
			(pinfunction "I2C4_CLK")
			(pintype "bidirectional")
		)
		(pad "D62" smd circle
			(at 27.7 3 90)
			(size 0.5 0.5)
			(layers "F.Cu" "F.Mask" "F.Paste")
			(net 109 "/Expansion connector/SPI2.MISO")
			(pinfunction "SPI2_MISO")
			(pintype "bidirectional")
		)
		(pad "D63" smd circle
			(at 28.6 3 90)
			(size 0.5 0.5)
			(layers "F.Cu" "F.Mask" "F.Paste")
			(net 1 "GND")
			(pinfunction "GND")
			(pintype "passive")
		)
		(pad "D64" smd circle
			(at 29.5 3 90)
			(size 0.5 0.5)
			(layers "F.Cu" "F.Mask" "F.Paste")
			(net 12 "SYS_VIN_HV")
			(pinfunction "SYS_VIN_HV")
			(pintype "passive")
		)
		(pad "D65" smd circle
			(at 30.4 3 90)
			(size 0.5 0.5)
			(layers "F.Cu" "F.Mask" "F.Paste")
			(net 12 "SYS_VIN_HV")
			(pinfunction "SYS_VIN_HV")
			(pintype "passive")
		)
		(pad "E1" smd circle
			(at -30.2 1.5 90)
			(size 0.5 0.5)
			(layers "F.Cu" "F.Mask" "F.Paste")
			(net 12 "SYS_VIN_HV")
			(pinfunction "SYS_VIN_HV")
			(pintype "passive")
		)
		(pad "E2" smd circle
			(at -29.3 1.5 90)
			(size 0.5 0.5)
			(layers "F.Cu" "F.Mask" "F.Paste")
			(net 12 "SYS_VIN_HV")
			(pinfunction "SYS_VIN_HV")
			(pintype "passive")
		)
		(pad "E3" smd circle
			(at -28.4 1.5 90)
			(size 0.5 0.5)
			(layers "F.Cu" "F.Mask" "F.Paste")
			(net 1 "GND")
			(pinfunction "GND")
			(pintype "passive")
		)
		(pad "E4" smd circle
			(at -27.5 1.5 90)
			(size 0.5 0.5)
			(layers "F.Cu" "F.Mask" "F.Paste")
			(net 146 "/Expansion connector/I2S2.FS")
			(pinfunction "I2S2_FS")
			(pintype "bidirectional")
		)
		(pad "E5" smd circle
			(at -26.6 1.5 90)
			(size 0.5 0.5)
			(layers "F.Cu" "F.Mask" "F.Paste")
			(net 1292 "/SoM_IO/GPIO_EXP_IRQ_1V8")
			(pinfunction "GPIO44")
			(pintype "passive")
		)
		(pad "E6" smd circle
			(at -25.7 1.5 90)
			(size 0.5 0.5)
			(layers "F.Cu" "F.Mask" "F.Paste")
			(net 882 "unconnected-(J1I-SGMII0_MDC-PadE6)")
			(pinfunction "SGMII0_MDC")
			(pintype "output+no_connect")
		)
		(pad "E7" smd circle
			(at -24.8 1.5 90)
			(size 0.5 0.5)
			(layers "F.Cu" "F.Mask" "F.Paste")
			(net 670 "unconnected-(J1I-SGMII0_MDIO-PadE7)")
			(pinfunction "SGMII0_MDIO")
			(pintype "bidirectional+no_connect")
		)
		(pad "E8" smd circle
			(at -23.9 1.5 90)
			(size 0.5 0.5)
			(layers "F.Cu" "F.Mask" "F.Paste")
			(net 740 "unconnected-(J1I-FSI_GPIO35-PadE8)")
			(pinfunction "FSI_GPIO35")
			(pintype "bidirectional+no_connect")
		)
		(pad "E9" smd circle
			(at -23 1.5 90)
			(size 0.5 0.5)
			(layers "F.Cu" "F.Mask" "F.Paste")
			(net 1 "GND")
			(pinfunction "GND")
			(pintype "passive")
		)
		(pad "E10" smd circle
			(at -22.1 1.5 90)
			(size 0.5 0.5)
			(layers "F.Cu" "F.Mask" "F.Paste")
			(net 686 "unconnected-(J1H-GPIO12-PadE10)")
			(pinfunction "GPIO12")
			(pintype "bidirectional+no_connect")
		)
		(pad "E11" smd circle
			(at -21.2 1.5 90)
			(size 0.5 0.5)
			(layers "F.Cu" "F.Mask" "F.Paste")
			(net 694 "/Expansion connector/PCIe_{C2x1}.~{CLKREQ}")
			(pinfunction "PEX_C2_CLKREQ_N")
			(pintype "bidirectional")
		)
		(pad "E12" smd circle
			(at -20.3 1.5 90)
			(size 0.5 0.5)
			(layers "F.Cu" "F.Mask" "F.Paste")
			(net 1 "GND")
			(pinfunction "GND")
			(pintype "passive")
		)
		(pad "E13" smd circle
			(at -19 1.5 90)
			(size 0.5 0.5)
			(layers "F.Cu" "F.Mask" "F.Paste")
			(net 1 "GND")
			(pinfunction "GND")
			(pintype "passive")
		)
		(pad "E14" smd circle
			(at -18.1 1.5 90)
			(size 0.5 0.5)
			(layers "F.Cu" "F.Mask" "F.Paste")
			(net 668 "/SoM_IO2/PCIe_{C2x1}R_CLK-")
			(pinfunction "UPHY_REFCLK5_N")
			(pintype "bidirectional")
		)
		(pad "E15" smd circle
			(at -17.2 1.5 90)
			(size 0.5 0.5)
			(layers "F.Cu" "F.Mask" "F.Paste")
			(net 720 "/SoM_IO2/PCIe_{C2x1}R_CLK+")
			(pinfunction "UPHY_REFCLK5_P")
			(pintype "bidirectional")
		)
		(pad "E16" smd circle
			(at -16.3 1.5 90)
			(size 0.5 0.5)
			(layers "F.Cu" "F.Mask" "F.Paste")
			(net 1 "GND")
			(pinfunction "GND")
			(pintype "passive")
		)
		(pad "E17" smd circle
			(at -15 1.5 90)
			(size 0.5 0.5)
			(layers "F.Cu" "F.Mask" "F.Paste")
			(net 1 "GND")
			(pinfunction "GND")
			(pintype "passive")
		)
		(pad "E18" smd circle
			(at -14.1 1.5 90)
			(size 0.5 0.5)
			(layers "F.Cu" "F.Mask" "F.Paste")
			(net 1263 "/SoM_IO2/DP2.AUX_C-")
			(pinfunction "DP_AUX_CH2_N")
			(pintype "bidirectional")
		)
		(pad "E19" smd circle
			(at -13.2 1.5 90)
			(size 0.5 0.5)
			(layers "F.Cu" "F.Mask" "F.Paste")
			(net 1262 "/SoM_IO2/DP2.AUX_C+")
			(pinfunction "DP_AUX_CH2_P")
			(pintype "bidirectional")
		)
		(pad "E20" smd circle
			(at -12.3 1.5 90)
			(size 0.5 0.5)
			(layers "F.Cu" "F.Mask" "F.Paste")
			(net 1 "GND")
			(pinfunction "GND")
			(pintype "passive")
		)
		(pad "E21" smd circle
			(at -11 1.5 90)
			(size 0.5 0.5)
			(layers "F.Cu" "F.Mask" "F.Paste")
			(net 1 "GND")
			(pinfunction "GND")
			(pintype "passive")
		)
		(pad "E22" smd circle
			(at -10.1 1.5 90)
			(size 0.5 0.5)
			(layers "F.Cu" "F.Mask" "F.Paste")
			(net 732 "/Expansion connector/PCIe_{C3x2}.CLK-")
			(pinfunction "UPHY_REFCLK4_N")
			(pintype "output")
		)
		(pad "E23" smd circle
			(at -9.2 1.5 90)
			(size 0.5 0.5)
			(layers "F.Cu" "F.Mask" "F.Paste")
			(net 699 "/Expansion connector/PCIe_{C3x2}.CLK+")
			(pinfunction "UPHY_REFCLK4_P")
			(pintype "output")
		)
		(pad "E24" smd circle
			(at -8.3 1.5 90)
			(size 0.5 0.5)
			(layers "F.Cu" "F.Mask" "F.Paste")
			(net 1 "GND")
			(pinfunction "GND")
			(pintype "passive")
		)
		(pad "E25" smd circle
			(at -7 1.5 90)
			(size 0.5 0.5)
			(layers "F.Cu" "F.Mask" "F.Paste")
			(net 1 "GND")
			(pinfunction "GND")
			(pintype "passive")
		)
		(pad "E26" smd circle
			(at -6.1 1.5 90)
			(size 0.5 0.5)
			(layers "F.Cu" "F.Mask" "F.Paste")
			(net 842 "/Expansion connector/I2C7.SDA")
			(pinfunction "I2C7_DAT")
			(pintype "bidirectional")
		)
		(pad "E27" smd circle
			(at -5.2 1.5 90)
			(size 0.5 0.5)
			(layers "F.Cu" "F.Mask" "F.Paste")
			(net 866 "/Expansion connector/I2C7.SCL")
			(pinfunction "I2C7_CLK")
			(pintype "bidirectional")
		)
		(pad "E28" smd circle
			(at -4.3 1.5 90)
			(size 0.5 0.5)
			(layers "F.Cu" "F.Mask" "F.Paste")
			(net 1 "GND")
			(pinfunction "GND")
			(pintype "passive")
		)
		(pad "E29" smd circle
			(at -3 1.5 90)
			(size 0.5 0.5)
			(layers "F.Cu" "F.Mask" "F.Paste")
			(net 1 "GND")
			(pinfunction "GND")
			(pintype "passive")
		)
		(pad "E30" smd circle
			(at -2.1 1.5 90)
			(size 0.5 0.5)
			(layers "F.Cu" "F.Mask" "F.Paste")
			(net 568 "unconnected-(J1G-FSI_GPIO24-PadE30)")
			(pinfunction "FSI_GPIO24")
			(pintype "passive+no_connect")
		)
		(pad "E31" smd circle
			(at -1.2 1.5 90)
			(size 0.5 0.5)
			(layers "F.Cu" "F.Mask" "F.Paste")
			(net 711 "unconnected-(J1G-FSI_GPIO23-PadE31)")
			(pinfunction "FSI_GPIO23")
			(pintype "passive+no_connect")
		)
		(pad "E32" smd circle
			(at -0.3 1.5 90)
			(size 0.5 0.5)
			(layers "F.Cu" "F.Mask" "F.Paste")
			(net 1 "GND")
			(pinfunction "GND")
			(pintype "passive")
		)
		(pad "E33" smd circle
			(at 1 1.5 90)
			(size 0.5 0.5)
			(layers "F.Cu" "F.Mask" "F.Paste")
			(net 1 "GND")
			(pinfunction "GND")
			(pintype "passive")
		)
		(pad "E34" smd circle
			(at 1.9 1.5 90)
			(size 0.5 0.5)
			(layers "F.Cu" "F.Mask" "F.Paste")
			(net 710 "unconnected-(J1I-FSI_GPIO15-PadE34)")
			(pinfunction "FSI_GPIO15")
			(pintype "passive+no_connect")
		)
		(pad "E35" smd circle
			(at 2.8 1.5 90)
			(size 0.5 0.5)
			(layers "F.Cu" "F.Mask" "F.Paste")
			(net 785 "unconnected-(J1I-FSI_GPIO14-PadE35)")
			(pinfunction "FSI_GPIO14")
			(pintype "passive+no_connect")
		)
		(pad "E36" smd circle
			(at 3.7 1.5 90)
			(size 0.5 0.5)
			(layers "F.Cu" "F.Mask" "F.Paste")
			(net 1 "GND")
			(pinfunction "GND")
			(pintype "passive")
		)
		(pad "E37" smd circle
			(at 5 1.5 90)
			(size 0.5 0.5)
			(layers "F.Cu" "F.Mask" "F.Paste")
			(net 1 "GND")
			(pinfunction "GND")
			(pintype "passive")
		)
		(pad "E38" smd circle
			(at 5.9 1.5 90)
			(size 0.5 0.5)
			(layers "F.Cu" "F.Mask" "F.Paste")
			(net 153 "/CSI/CAM1.CSI0_D1-")
			(pinfunction "CSI0_D1_N")
			(pintype "input")
		)
		(pad "E39" smd circle
			(at 6.8 1.5 90)
			(size 0.5 0.5)
			(layers "F.Cu" "F.Mask" "F.Paste")
			(net 54 "/CSI/CAM1.CSI0_D1+")
			(pinfunction "CSI0_D1_P")
			(pintype "input")
		)
		(pad "E40" smd circle
			(at 7.7 1.5 90)
			(size 0.5 0.5)
			(layers "F.Cu" "F.Mask" "F.Paste")
			(net 1 "GND")
			(pinfunction "GND")
			(pintype "passive")
		)
		(pad "E41" smd circle
			(at 8.6 1.5 90)
			(size 0.5 0.5)
			(layers "F.Cu" "F.Mask" "F.Paste")
			(net 113 "/CSI/CAM1.CSI0_D0-")
			(pinfunction "CSI0_D0_N")
			(pintype "input")
		)
		(pad "E42" smd circle
			(at 9.5 1.5 90)
			(size 0.5 0.5)
			(layers "F.Cu" "F.Mask" "F.Paste")
			(net 157 "/CSI/CAM1.CSI0_D0+")
			(pinfunction "CSI0_D0_P")
			(pintype "input")
		)
		(pad "E43" smd circle
			(at 10.4 1.5 90)
			(size 0.5 0.5)
			(layers "F.Cu" "F.Mask" "F.Paste")
			(net 1 "GND")
			(pinfunction "GND")
			(pintype "passive")
		)
		(pad "E44" smd circle
			(at 11.3 1.5 90)
			(size 0.5 0.5)
			(layers "F.Cu" "F.Mask" "F.Paste")
			(net 63 "/CSI/CAM0.CSI3_D0-")
			(pinfunction "CSI3_D0_N")
			(pintype "input")
		)
		(pad "E45" smd circle
			(at 12.2 1.5 90)
			(size 0.5 0.5)
			(layers "F.Cu" "F.Mask" "F.Paste")
			(net 52 "/CSI/CAM0.CSI3_D0+")
			(pinfunction "CSI3_D0_P")
			(pintype "input")
		)
		(pad "E46" smd circle
			(at 13.1 1.5 90)
			(size 0.5 0.5)
			(layers "F.Cu" "F.Mask" "F.Paste")
			(net 1 "GND")
			(pinfunction "GND")
			(pintype "passive")
		)
		(pad "E47" smd circle
			(at 14 1.5 90)
			(size 0.5 0.5)
			(layers "F.Cu" "F.Mask" "F.Paste")
			(net 87 "/CSI/CAM2.CSI4_D1+")
			(pinfunction "CSI4_D1_P")
			(pintype "input")
		)
		(pad "E48" smd circle
			(at 14.9 1.5 90)
			(size 0.5 0.5)
			(layers "F.Cu" "F.Mask" "F.Paste")
			(net 162 "/CSI/CAM2.CSI4_D1-")
			(pinfunction "CSI4_D1_N")
			(pintype "input")
		)
		(pad "E49" smd circle
			(at 15.8 1.5 90)
			(size 0.5 0.5)
			(layers "F.Cu" "F.Mask" "F.Paste")
			(net 1 "GND")
			(pinfunction "GND")
			(pintype "passive")
		)
		(pad "E50" smd circle
			(at 16.7 1.5 90)
			(size 0.5 0.5)
			(layers "F.Cu" "F.Mask" "F.Paste")
			(net 798 "unconnected-(J1I-FSI_GPIO19-PadE50)")
			(pinfunction "FSI_GPIO19")
			(pintype "bidirectional+no_connect")
		)
		(pad "E51" smd circle
			(at 17.6 1.5 90)
			(size 0.5 0.5)
			(layers "F.Cu" "F.Mask" "F.Paste")
			(net 735 "unconnected-(J1I-FSI_GPIO18-PadE51)")
			(pinfunction "FSI_GPIO18")
			(pintype "output+no_connect")
		)
		(pad "E52" smd circle
			(at 18.5 1.5 90)
			(size 0.5 0.5)
			(layers "F.Cu" "F.Mask" "F.Paste")
			(net 1 "GND")
			(pinfunction "GND")
			(pintype "passive")
		)
		(pad "E53" smd circle
			(at 19.4 1.5 90)
			(size 0.5 0.5)
			(layers "F.Cu" "F.Mask" "F.Paste")
			(net 145 "/SoM_IO/I2C3_SDA_1V8")
			(pinfunction "I2C3_DAT")
			(pintype "bidirectional")
		)
		(pad "E54" smd circle
			(at 20.3 1.5 90)
			(size 0.5 0.5)
			(layers "F.Cu" "F.Mask" "F.Paste")
			(net 100 "/Peripherals/FAN_TACH")
			(pinfunction "FAN_TACH")
			(pintype "input")
		)
		(pad "E55" smd circle
			(at 21.2 1.5 90)
			(size 0.5 0.5)
			(layers "F.Cu" "F.Mask" "F.Paste")
			(net 292 "/Expansion connector/SPI1.~{CS0}")
			(pinfunction "SPI1_CS0_N")
			(pintype "bidirectional")
		)
		(pad "E56" smd circle
			(at 22.1 1.5 90)
			(size 0.5 0.5)
			(layers "F.Cu" "F.Mask" "F.Paste")
			(net 405 "/Expansion connector/SPI3.~{CS1}")
			(pinfunction "SPI3_CS1_N")
			(pintype "bidirectional")
		)
		(pad "E57" smd circle
			(at 23 1.5 90)
			(size 0.5 0.5)
			(layers "F.Cu" "F.Mask" "F.Paste")
			(net 1 "GND")
			(pinfunction "GND")
			(pintype "passive")
		)
		(pad "E58" smd circle
			(at 23.9 1.5 90)
			(size 0.5 0.5)
			(layers "F.Cu" "F.Mask" "F.Paste")
			(net 706 "/SoM_IO2/JTAG_TMS")
			(pinfunction "JTAG_TMS")
			(pintype "passive")
		)
		(pad "E59" smd circle
			(at 24.8 1.5 90)
			(size 0.5 0.5)
			(layers "F.Cu" "F.Mask" "F.Paste")
			(net 1295 "unconnected-(J1K-GPIO38-PadE59)")
			(pinfunction "GPIO38")
			(pintype "passive+no_connect")
		)
		(pad "E60" smd circle
			(at 25.7 1.5 90)
			(size 0.5 0.5)
			(layers "F.Cu" "F.Mask" "F.Paste")
			(net 981 "/CSI/I2C_{CAM}.SDA")
			(pinfunction "I2C4_DAT")
			(pintype "bidirectional")
		)
		(pad "E61" smd circle
			(at 26.6 1.5 90)
			(size 0.5 0.5)
			(layers "F.Cu" "F.Mask" "F.Paste")
			(net 393 "/Expansion connector/SPI2.SCK")
			(pinfunction "SPI2_CLK")
			(pintype "bidirectional")
		)
		(pad "E62" smd circle
			(at 27.5 1.5 90)
			(size 0.5 0.5)
			(layers "F.Cu" "F.Mask" "F.Paste")
			(net 1 "GND")
			(pinfunction "GND")
			(pintype "passive")
		)
		(pad "E63" smd circle
			(at 28.4 1.5 90)
			(size 0.5 0.5)
			(layers "F.Cu" "F.Mask" "F.Paste")
			(net 12 "SYS_VIN_HV")
			(pinfunction "SYS_VIN_HV")
			(pintype "passive")
		)
		(pad "E64" smd circle
			(at 29.3 1.5 90)
			(size 0.5 0.5)
			(layers "F.Cu" "F.Mask" "F.Paste")
			(net 12 "SYS_VIN_HV")
			(pinfunction "SYS_VIN_HV")
			(pintype "passive")
		)
		(pad "E65" smd circle
			(at 30.2 1.5 90)
			(size 0.5 0.5)
			(layers "F.Cu" "F.Mask" "F.Paste")
			(net 12 "SYS_VIN_HV")
			(pinfunction "SYS_VIN_HV")
			(pintype "passive")
		)
		(pad "F1" smd circle
			(at -30 0 90)
			(size 0.5 0.5)
			(layers "F.Cu" "F.Mask" "F.Paste")
			(net 12 "SYS_VIN_HV")
			(pinfunction "SYS_VIN_HV")
			(pintype "passive")
		)
		(pad "F2" smd circle
			(at -29.1 0 90)
			(size 0.5 0.5)
			(layers "F.Cu" "F.Mask" "F.Paste")
			(net 12 "SYS_VIN_HV")
			(pinfunction "SYS_VIN_HV")
			(pintype "passive")
		)
		(pad "F3" smd circle
			(at -28.2 0 90)
			(size 0.5 0.5)
			(layers "F.Cu" "F.Mask" "F.Paste")
			(net 12 "SYS_VIN_HV")
			(pinfunction "SYS_VIN_HV")
			(pintype "passive")
		)
		(pad "F4" smd circle
			(at -27.3 0 90)
			(size 0.5 0.5)
			(layers "F.Cu" "F.Mask" "F.Paste")
			(net 1 "GND")
			(pinfunction "GND")
			(pintype "passive")
		)
		(pad "F5" smd circle
			(at -26.4 0 90)
			(size 0.5 0.5)
			(layers "F.Cu" "F.Mask" "F.Paste")
			(net 172 "/Expansion connector/I2S2.SDOUT")
			(pinfunction "I2S2_DOUT")
			(pintype "output")
		)
	)
)
